# BASEBOARD_FAB2 (Tioga Pass) — schematic netlist excerpt (pin names and nets, part order shuffled) for the footprints in the layout excerpt that follows; sources: Cadence DE-HDL packaged netlist, KiCad conversion of Wiwynn_Tioga_Pass_MB.brd

J1A1  SCONN288_H44441004  SCONN  pkg PIP  page 87
  \12v\(1)  = P12V_NVDIMM_KLM
  VSS(93)  = GND
  DQ(4)  = M_M_DQ<5>
  VSS(92)  = GND
  DQ(0)  = M_M_DQ<1>
  VSS(91)  = GND
  DQS9P  = M_M_DQS_DP<9>
  DQS9N  = M_M_DQS_DN<9>
  VSS(90)  = GND
  DQ(6)  = M_M_DQ<7>
  VSS(89)  = GND
  DQ(2)  = M_M_DQ<3>
  VSS(88)  = GND
  DQ(12)  = M_M_DQ<13>
  VSS(87)  = GND
  DQ(8)  = M_M_DQ<9>
  VSS(86)  = GND
  DQS10P  = M_M_DQS_DP<10>
  DQS10N  = M_M_DQS_DN<10>
  VSS(85)  = GND
  DQ(14)  = M_M_DQ<15>
  VSS(84)  = GND
  DQ(10)  = M_M_DQ<11>
  VSS(83)  = GND
  DQ(20)  = M_M_DQ<21>
  VSS(82)  = GND
  DQ(16)  = M_M_DQ<17>
  VSS(81)  = GND
  DQS11P  = M_M_DQS_DP<11>
  DQS11N  = M_M_DQS_DN<11>
  VSS(80)  = GND
  DQ(22)  = M_M_DQ<23>
  VSS(79)  = GND
  DQ(18)  = M_M_DQ<19>
  VSS(78)  = GND
  DQ(28)  = M_M_DQ<29>
  VSS(77)  = GND
  DQ(24)  = M_M_DQ<25>
  VSS(76)  = GND
  DQS12P  = M_M_DQS_DP<12>
  DQS12N  = M_M_DQS_DN<12>
  VSS(75)  = GND
  DQ(30)  = M_M_DQ<31>
  VSS(74)  = GND
  DQ(26)  = M_M_DQ<27>
  VSS(73)  = GND
  CB(4)  = M_M_ECC<5>
  VSS(72)  = GND
  CB(0)  = M_M_ECC<1>
  VSS(71)  = GND
  DQS17P  = M_M_DQS_DP<17>
  DQS17N  = M_M_DQS_DN<17>
  VSS(70)  = GND
  CB(6)  = M_M_ECC<7>
  VSS(69)  = GND
  CB(2)  = M_M_ECC<3>
  VSS(68)  = GND
  RESET_N  = M_KLM_RST_N
  VDD(25)  = PVDDQ_KLM
  CKE(0)  = M_M_CKE<0>
  VDD(24)  = PVDDQ_KLM
  ACT_N  = M_M_ACT_N
  BG(0)  = M_M_BG<0>
  VDD(23)  = PVDDQ_KLM
  A12  = M_M_MA<12>
  A9  = M_M_MA<9>
  VDD(22)  = PVDDQ_KLM
  A8  = M_M_MA<8>
  A6  = M_M_MA<6>
  VDD(21)  = PVDDQ_KLM
  A3  = M_M_MA<3>
  A1  = M_M_MA<1>
  VDD(20)  = PVDDQ_KLM
  CK0P  = M_M_CLK_DP<0>
  CK0N  = M_M_CLK_DN<0>
  VDD(19)  = PVDDQ_KLM
  VTT(1)  = PVTT_KLM
  EVENT_N  = FM_DIMM_EVENT_COD_N
  A0  = M_M_MA<0>
  VDD(18)  = PVDDQ_KLM
  BA(0)  = M_M_BA<0>
  A16_RAS_N  = M_M_MA<16>
  VDD(17)  = PVDDQ_KLM
  S0_N  = M_M_CS_N<0>
  VDD(16)  = PVDDQ_KLM
  A15_CAS_N  = M_M_MA<15>
  ODT(0)  = M_M_ODT<0>
  VDD(15)  = PVDDQ_KLM
  S1_N  = M_M_CS_N<1>
  VDD(14)  = PVDDQ_KLM
  ODT(1)  = M_M_ODT<1>
  VDD(13)  = PVDDQ_KLM
  S2_N_C(0)  = M_M_CS_N<2>
  VSS(67)  = GND
  DQ(36)  = M_M_DQ<37>
  VSS(66)  = GND
  DQ(32)  = M_M_DQ<33>
  VSS(65)  = GND
  DQS13P  = M_M_DQS_DP<13>
  DQS13N  = M_M_DQS_DN<13>
  VSS(64)  = GND
  DQ(38)  = M_M_DQ<39>
  VSS(63)  = GND
  DQ(34)  = M_M_DQ<35>
  VSS(62)  = GND
  DQ(44)  = M_M_DQ<45>
  VSS(61)  = GND
  DQ(40)  = M_M_DQ<41>
  VSS(60)  = GND
  DQS14P  = M_M_DQS_DP<14>
  DQS14N  = M_M_DQS_DN<14>
  VSS(59)  = GND
  DQ(46)  = M_M_DQ<47>
  VSS(58)  = GND
  DQ(42)  = M_M_DQ<43>
  VSS(57)  = GND
  DQ(52)  = M_M_DQ<53>
  VSS(56)  = GND
  DQ(48)  = M_M_DQ<49>
  VSS(55)  = GND
  DQS15P  = M_M_DQS_DP<15>
  DQS15N  = M_M_DQS_DN<15>
  VSS(54)  = GND
  DQ(54)  = M_M_DQ<55>
  VSS(53)  = GND
  DQ(50)  = M_M_DQ<51>
  VSS(52)  = GND
  DQ(60)  = M_M_DQ<61>
  VSS(51)  = GND
  DQ(56)  = M_M_DQ<57>
  VSS(50)  = GND
  DQS16P  = M_M_DQS_DP<16>
  DQS16N  = M_M_DQS_DN<16>
  VSS(49)  = GND
  DQ(62)  = M_M_DQ<63>
  VSS(48)  = GND
  DQ(58)  = M_M_DQ<59>
  VSS(47)  = GND
  SA(0)  = GND
  SA(1)  = GND
  SCL  = SMB_DDR_KLM_VPP_SCL
  VPP(4)  = PVPP_KLM
  VPP(3)  = PVPP_KLM
  RFU(2)  = TP_CH_M_DIMM_M0_RFU_2
  \12v\(0)  = P12V_NVDIMM_KLM
  VREFCA  = M_M_VREF
  VSS(46)  = GND
  DQ(5)  = M_M_DQ<4>
  VSS(45)  = GND
  DQ(1)  = M_M_DQ<0>
  VSS(44)  = GND
  DQS0N  = M_M_DQS_DN<0>
  DQS0P  = M_M_DQS_DP<0>
  VSS(43)  = GND
  DQ(7)  = M_M_DQ<6>
  VSS(42)  = GND
  DQ(3)  = M_M_DQ<2>
  VSS(41)  = GND
  DQ(13)  = M_M_DQ<12>
  VSS(40)  = GND
  DQ(9)  = M_M_DQ<8>
  VSS(39)  = GND
  DQS1N  = M_M_DQS_DN<1>
  DQS1P  = M_M_DQS_DP<1>
  VSS(38)  = GND
  DQ(15)  = M_M_DQ<14>
  VSS(37)  = GND
  DQ(11)  = M_M_DQ<10>
  VSS(36)  = GND
  DQ(21)  = M_M_DQ<20>
  VSS(35)  = GND
  DQ(17)  = M_M_DQ<16>
  VSS(34)  = GND
  DQS2N  = M_M_DQS_DN<2>
  DQS2P  = M_M_DQS_DP<2>
  VSS(33)  = GND
  DQ(23)  = M_M_DQ<22>
  VSS(32)  = GND
  DQ(19)  = M_M_DQ<18>
  VSS(31)  = GND
  DQ(29)  = M_M_DQ<28>
  VSS(30)  = GND
  DQ(25)  = M_M_DQ<24>
  VSS(29)  = GND
  DQS3N  = M_M_DQS_DN<3>
  DQS3P  = M_M_DQS_DP<3>
  VSS(28)  = GND
  DQ(31)  = M_M_DQ<30>
  VSS(27)  = GND
  DQ(27)  = M_M_DQ<26>
  VSS(26)  = GND
  CB(5)  = M_M_ECC<4>
  VSS(25)  = GND
  CB(1)  = M_M_ECC<0>
  VSS(24)  = GND
  DQS8N  = M_M_DQS_DN<8>
  DQS8P  = M_M_DQS_DP<8>
  VSS(23)  = GND
  CB(7)  = M_M_ECC<6>
  VSS(22)  = GND
  CB(3)  = M_M_ECC<2>
  VSS(21)  = GND
  CKE(1)  = M_M_CKE<1>
  VDD(12)  = PVDDQ_KLM
  RFU(0)  = TP_CH_M_DIMM_M0_RFU_0
  VDD(11)  = PVDDQ_KLM
  BG(1)  = M_M_BG<1>
  ALERT_N  = M_M_ALERT_N
  VDD(10)  = PVDDQ_KLM
  A11  = M_M_MA<11>
  A7  = M_M_MA<7>
  VDD(9)  = PVDDQ_KLM
  A5  = M_M_MA<5>
  A4  = M_M_MA<4>
  VDD(8)  = PVDDQ_KLM
  A2  = M_M_MA<2>
  VDD(7)  = PVDDQ_KLM
  CK1P  = M_M_CLK_DP<1>
  CK1N  = M_M_CLK_DN<1>
  VDD(6)  = PVDDQ_KLM
  VTT(0)  = PVTT_KLM
  PAR  = M_M_PAR
  VDD(5)  = PVDDQ_KLM
  BA(1)  = M_M_BA<1>
  A10  = M_M_MA<10>
  VDD(4)  = PVDDQ_KLM
  RFU(1)  = TP_CH_M_DIMM_M0_RFU_1
  A14_WE_N  = M_M_MA<14>
  VDD(3)  = PVDDQ_KLM
  SAVE_N_NC  = FM_ADR_COMPLETE_KLM_N
  VDD(2)  = PVDDQ_KLM
  A13  = M_M_MA<13>
  VDD(1)  = PVDDQ_KLM
  A17  = M_M_MA<17>
  C(2)  = M_M_C<2>
  VDD(0)  = PVDDQ_KLM
  S3_N_C(1)  = M_M_CS_N<3>
  SA(2)  = PVPP_KLM
  VSS(20)  = GND
  DQ(37)  = M_M_DQ<36>
  VSS(19)  = GND
  DQ(33)  = M_M_DQ<32>
  VSS(18)  = GND
  DQS4N  = M_M_DQS_DN<4>
  DQS4P  = M_M_DQS_DP<4>
  VSS(17)  = GND
  DQ(39)  = M_M_DQ<38>
  VSS(16)  = GND
  DQ(35)  = M_M_DQ<34>
  VSS(15)  = GND
  DQ(45)  = M_M_DQ<44>
  VSS(14)  = GND
  DQ(41)  = M_M_DQ<40>
  VSS(13)  = GND
  DQS5N  = M_M_DQS_DN<5>
  DQS5P  = M_M_DQS_DP<5>
  VSS(12)  = GND
  DQ(47)  = M_M_DQ<46>
  VSS(11)  = GND
  DQ(43)  = M_M_DQ<42>
  VSS(10)  = GND
  DQ(53)  = M_M_DQ<52>
  VSS(9)  = GND
  DQ(49)  = M_M_DQ<48>
  VSS(8)  = GND
  DQS6N  = M_M_DQS_DN<6>
  DQS6P  = M_M_DQS_DP<6>
  VSS(7)  = GND
  DQ(55)  = M_M_DQ<54>
  VSS(6)  = GND
  DQ(51)  = M_M_DQ<50>
  VSS(5)  = GND
  DQ(61)  = M_M_DQ<60>
  VSS(4)  = GND
  DQ(57)  = M_M_DQ<56>
  VSS(3)  = GND
  DQS7N  = M_M_DQS_DN<7>
  DQS7P  = M_M_DQS_DP<7>
  VSS(2)  = GND
  DQ(63)  = M_M_DQ<62>
  VSS(1)  = GND
  DQ(59)  = M_M_DQ<58>
  VSS(0)  = GND
  VDDSPD  = PVPP_KLM
  SDA  = SMB_DDR_KLM_VPP_SDA
  VPP(1)  = PVPP_KLM
  VPP(0)  = PVPP_KLM
  VPP(2)  = PVPP_KLM

(kicad_pcb
	(version 20260206)
	(generator "pcbnew")
	(generator_version "10.0")
	(general
		(thickness 1.6)
		(legacy_teardrops no)
	)
	(paper "A4")
	(title_block
		(title "Wiwynn_Tioga_Pass_MB.brd")
		(comment 1 "Tioga Pass / footprint 830 of 4770 (J1A1), pads 203-251 of 291")
	)
	(layers
		(0 "F.Cu" signal "TOP")
		(4 "In1.Cu" signal "L2GND")
		(6 "In2.Cu" signal "L3")
		(8 "In3.Cu" signal "L4GND")
		(10 "In4.Cu" signal "L5")
		(12 "In5.Cu" signal "L6GND")
		(14 "In6.Cu" signal "L7VCC")
		(16 "In7.Cu" signal "L8VCC")
		(18 "In8.Cu" signal "L9GND")
		(20 "In9.Cu" signal "L10")
		(22 "In10.Cu" signal "L11GND")
		(24 "In11.Cu" signal "L12")
		(26 "In12.Cu" signal "L13GND")
		(2 "B.Cu" signal "BOTTOM")
		(9 "F.Adhes" user "F.Adhesive")
		(11 "B.Adhes" user "B.Adhesive")
		(13 "F.Paste" user "Package Geometry/Pastemask Top")
		(15 "B.Paste" user "Package Geometry/Pastemask Bottom")
		(5 "F.SilkS" user "Ref Des/Silkscreen Top")
		(7 "B.SilkS" user "Ref Des/Silkscreen Bottom")
		(1 "F.Mask" user "Board Geometry/Soldermask Top")
		(3 "B.Mask" user "Board Geometry/Soldermask Bottom")
		(17 "Dwgs.User" user "User.Drawings")
		(19 "Cmts.User" user "User.Comments")
		(21 "Eco1.User" user "User.Eco1")
		(23 "Eco2.User" user "User.Eco2")
		(25 "Edge.Cuts" user "Board Geometry/Outline")
		(27 "Margin" user)
		(31 "F.CrtYd" user "Package Geometry/Place Bound Top")
		(29 "B.CrtYd" user "Package Geometry/Place Bound Bottom")
		(35 "F.Fab" user "Ref Des/Assembly Top")
		(33 "B.Fab" user "Ref Des/Assembly Bottom")
	)
	(footprint ""
		(layer "F.Cu")
		(at 29.699458 -152.273 90)
		(property "Reference" "J1A1"
			(at -2.572512 42.563542 0)
			(unlocked yes)
			(layer "F.SilkS")
			(effects
				(font
					(size 0.7874 0.5842)
					(thickness 0.1524)
				)
				(justify left)
			)
		)
		(property "Value" ""
			(at 0 0 90)
			(layer "F.Fab")
			(effects
				(font
					(size 1.27 1.27)
				)
			)
		)
		(duplicate_pad_numbers_are_jumpers no)
		(pad "200" smd rect
			(at 4.59994 46.74997 90)
			(size 1.8034 0.508)
			(layers "F.Cu" "F.Mask" "F.Paste")
			(net "GND")
		)
		(pad "201" smd rect
			(at 4.59994 47.600108 90)
			(size 1.8034 0.508)
			(layers "F.Cu" "F.Mask" "F.Paste")
			(net "M_M_ECC<2>")
		)
		(pad "202" smd rect
			(at 4.59994 48.449992 90)
			(size 1.8034 0.508)
			(layers "F.Cu" "F.Mask" "F.Paste")
			(net "GND")
		)
		(pad "203" smd rect
			(at 4.59994 49.299876 90)
			(size 1.8034 0.508)
			(layers "F.Cu" "F.Mask" "F.Paste")
			(net "M_M_CKE<1>")
		)
		(pad "204" smd rect
			(at 4.59994 50.150014 90)
			(size 1.8034 0.508)
			(layers "F.Cu" "F.Mask" "F.Paste")
			(net "PVDDQ_KLM")
		)
		(pad "205" smd rect
			(at 4.59994 50.999898 90)
			(size 1.8034 0.508)
			(layers "F.Cu" "F.Mask" "F.Paste")
			(net "TP_CH_M_DIMM_M0_RFU_0")
		)
		(pad "206" smd rect
			(at 4.59994 51.850036 90)
			(size 1.8034 0.508)
			(layers "F.Cu" "F.Mask" "F.Paste")
			(net "PVDDQ_KLM")
		)
		(pad "207" smd rect
			(at 4.59994 52.69992 90)
			(size 1.8034 0.508)
			(layers "F.Cu" "F.Mask" "F.Paste")
			(net "M_M_BG<1>")
		)
		(pad "208" smd rect
			(at 4.59994 53.550058 90)
			(size 1.8034 0.508)
			(layers "F.Cu" "F.Mask" "F.Paste")
			(net "M_M_ALERT_N")
		)
		(pad "209" smd rect
			(at 4.59994 54.399942 90)
			(size 1.8034 0.508)
			(layers "F.Cu" "F.Mask" "F.Paste")
			(net "PVDDQ_KLM")
		)
		(pad "210" smd rect
			(at 4.59994 55.25008 90)
			(size 1.8034 0.508)
			(layers "F.Cu" "F.Mask" "F.Paste")
			(net "M_M_MA<11>")
		)
		(pad "211" smd rect
			(at 4.59994 56.099964 90)
			(size 1.8034 0.508)
			(layers "F.Cu" "F.Mask" "F.Paste")
			(net "M_M_MA<7>")
		)
		(pad "212" smd rect
			(at 4.59994 56.950102 90)
			(size 1.8034 0.508)
			(layers "F.Cu" "F.Mask" "F.Paste")
			(net "PVDDQ_KLM")
		)
		(pad "213" smd rect
			(at 4.59994 57.799986 90)
			(size 1.8034 0.508)
			(layers "F.Cu" "F.Mask" "F.Paste")
			(net "M_M_MA<5>")
		)
		(pad "214" smd rect
			(at 4.59994 58.650124 90)
			(size 1.8034 0.508)
			(layers "F.Cu" "F.Mask" "F.Paste")
			(net "M_M_MA<4>")
		)
		(pad "215" smd rect
			(at 4.59994 59.500008 90)
			(size 1.8034 0.508)
			(layers "F.Cu" "F.Mask" "F.Paste")
			(net "PVDDQ_KLM")
		)
		(pad "216" smd rect
			(at 4.59994 60.349892 90)
			(size 1.8034 0.508)
			(layers "F.Cu" "F.Mask" "F.Paste")
			(net "M_M_MA<2>")
		)
		(pad "217" smd rect
			(at 4.59994 61.20003 90)
			(size 1.8034 0.508)
			(layers "F.Cu" "F.Mask" "F.Paste")
			(net "PVDDQ_KLM")
		)
		(pad "218" smd rect
			(at 4.59994 62.049914 90)
			(size 1.8034 0.508)
			(layers "F.Cu" "F.Mask" "F.Paste")
			(net "M_M_CLK_DP<1>")
		)
		(pad "219" smd rect
			(at 4.59994 62.900052 90)
			(size 1.8034 0.508)
			(layers "F.Cu" "F.Mask" "F.Paste")
			(net "M_M_CLK_DN<1>")
		)
		(pad "220" smd rect
			(at 4.59994 63.749936 90)
			(size 1.8034 0.508)
			(layers "F.Cu" "F.Mask" "F.Paste")
			(net "PVDDQ_KLM")
		)
		(pad "221" smd rect
			(at 4.59994 64.600074 90)
			(size 1.8034 0.508)
			(layers "F.Cu" "F.Mask" "F.Paste")
			(net "PVTT_KLM")
		)
		(pad "222" smd rect
			(at 4.59994 70.550024 90)
			(size 1.8034 0.508)
			(layers "F.Cu" "F.Mask" "F.Paste")
			(net "M_M_PAR")
		)
		(pad "223" smd rect
			(at 4.59994 71.399908 90)
			(size 1.8034 0.508)
			(layers "F.Cu" "F.Mask" "F.Paste")
			(net "PVDDQ_KLM")
		)
		(pad "224" smd rect
			(at 4.59994 72.250046 90)
			(size 1.8034 0.508)
			(layers "F.Cu" "F.Mask" "F.Paste")
			(net "M_M_BA<1>")
		)
		(pad "225" smd rect
			(at 4.59994 73.09993 90)
			(size 1.8034 0.508)
			(layers "F.Cu" "F.Mask" "F.Paste")
			(net "M_M_MA<10>")
		)
		(pad "226" smd rect
			(at 4.59994 73.950068 90)
			(size 1.8034 0.508)
			(layers "F.Cu" "F.Mask" "F.Paste")
			(net "PVDDQ_KLM")
		)
		(pad "227" smd rect
			(at 4.59994 74.799952 90)
			(size 1.8034 0.508)
			(layers "F.Cu" "F.Mask" "F.Paste")
			(net "TP_CH_M_DIMM_M0_RFU_1")
		)
		(pad "228" smd rect
			(at 4.59994 75.65009 90)
			(size 1.8034 0.508)
			(layers "F.Cu" "F.Mask" "F.Paste")
			(net "M_M_MA<14>")
		)
		(pad "229" smd rect
			(at 4.59994 76.499974 90)
			(size 1.8034 0.508)
			(layers "F.Cu" "F.Mask" "F.Paste")
			(net "PVDDQ_KLM")
		)
		(pad "230" smd rect
			(at 4.59994 77.350112 90)
			(size 1.8034 0.508)
			(layers "F.Cu" "F.Mask" "F.Paste")
			(net "FM_ADR_COMPLETE_KLM_N")
		)
		(pad "231" smd rect
			(at 4.59994 78.199996 90)
			(size 1.8034 0.508)
			(layers "F.Cu" "F.Mask" "F.Paste")
			(net "PVDDQ_KLM")
		)
		(pad "232" smd rect
			(at 4.59994 79.04988 90)
			(size 1.8034 0.508)
			(layers "F.Cu" "F.Mask" "F.Paste")
			(net "M_M_MA<13>")
		)
		(pad "233" smd rect
			(at 4.59994 79.900018 90)
			(size 1.8034 0.508)
			(layers "F.Cu" "F.Mask" "F.Paste")
			(net "PVDDQ_KLM")
		)
		(pad "234" smd rect
			(at 4.59994 80.749902 90)
			(size 1.8034 0.508)
			(layers "F.Cu" "F.Mask" "F.Paste")
			(net "M_M_MA<17>")
		)
		(pad "235" smd rect
			(at 4.59994 81.60004 90)
			(size 1.8034 0.508)
			(layers "F.Cu" "F.Mask" "F.Paste")
			(net "M_M_C<2>")
		)
		(pad "236" smd rect
			(at 4.59994 82.449924 90)
			(size 1.8034 0.508)
			(layers "F.Cu" "F.Mask" "F.Paste")
			(net "PVDDQ_KLM")
		)
		(pad "237" smd rect
			(at 4.59994 83.300062 90)
			(size 1.8034 0.508)
			(layers "F.Cu" "F.Mask" "F.Paste")
			(net "M_M_CS_N<3>")
		)
		(pad "238" smd rect
			(at 4.59994 84.149946 90)
			(size 1.8034 0.508)
			(layers "F.Cu" "F.Mask" "F.Paste")
			(net "PVPP_KLM")
		)
		(pad "239" smd rect
			(at 4.59994 85.000084 90)
			(size 1.8034 0.508)
			(layers "F.Cu" "F.Mask" "F.Paste")
			(net "GND")
		)
		(pad "240" smd rect
			(at 4.59994 85.849968 90)
			(size 1.8034 0.508)
			(layers "F.Cu" "F.Mask" "F.Paste")
			(net "M_M_DQ<36>")
		)
		(pad "241" smd rect
			(at 4.59994 86.700106 90)
			(size 1.8034 0.508)
			(layers "F.Cu" "F.Mask" "F.Paste")
			(net "GND")
		)
		(pad "242" smd rect
			(at 4.59994 87.54999 90)
			(size 1.8034 0.508)
			(layers "F.Cu" "F.Mask" "F.Paste")
			(net "M_M_DQ<32>")
		)
		(pad "243" smd rect
			(at 4.59994 88.399874 90)
			(size 1.8034 0.508)
			(layers "F.Cu" "F.Mask" "F.Paste")
			(net "GND")
		)
		(pad "244" smd rect
			(at 4.59994 89.250012 90)
			(size 1.8034 0.508)
			(layers "F.Cu" "F.Mask" "F.Paste")
			(net "M_M_DQS_DN<4>")
		)
		(pad "245" smd rect
			(at 4.59994 90.099896 90)
			(size 1.8034 0.508)
			(layers "F.Cu" "F.Mask" "F.Paste")
			(net "M_M_DQS_DP<4>")
		)
		(pad "246" smd rect
			(at 4.59994 90.950034 90)
			(size 1.8034 0.508)
			(layers "F.Cu" "F.Mask" "F.Paste")
			(net "GND")
		)
		(pad "247" smd rect
			(at 4.59994 91.799918 90)
			(size 1.8034 0.508)
			(layers "F.Cu" "F.Mask" "F.Paste")
			(net "M_M_DQ<38>")
		)
		(pad "248" smd rect
			(at 4.59994 92.650056 90)
			(size 1.8034 0.508)
			(layers "F.Cu" "F.Mask" "F.Paste")
			(net "GND")
		)
	)
)
